(kicad_pcb
	(version 20260206)
	(generator "pcbnew")
	(generator_version "10.0")
	(general
		(thickness 1.6)
		(legacy_teardrops no)
	)
	(paper "A4")
	(title_block
		(title "03242023_DA0F0TMBIJ0_F0T_Motherboard_J_brd_V01_OCP.brd")
		(comment 1 "Grand Teton / footprints 2099-2105 of 6105")
	)
	(layers
		(0 "F.Cu" signal "TOP")
		(4 "In1.Cu" signal "GND")
		(6 "In2.Cu" signal "IN1")
		(8 "In3.Cu" signal "GND1")
		(10 "In4.Cu" signal "IN2")
		(12 "In5.Cu" signal "GND2")
		(14 "In6.Cu" signal "IN3")
		(16 "In7.Cu" signal "GND3")
		(18 "In8.Cu" signal "VCC")
		(20 "In9.Cu" signal "VCC1")
		(22 "In10.Cu" signal "GND4")
		(24 "In11.Cu" signal "IN4")
		(26 "In12.Cu" signal "GND5")
		(28 "In13.Cu" signal "IN5")
		(30 "In14.Cu" signal "GND6")
		(32 "In15.Cu" signal "IN6")
		(34 "In16.Cu" signal "GND7")
		(2 "B.Cu" signal "BOTTOM")
		(9 "F.Adhes" user "F.Adhesive")
		(11 "B.Adhes" user "B.Adhesive")
		(13 "F.Paste" user "Package Geometry/Pastemask Top")
		(15 "B.Paste" user "Package Geometry/Pastemask Bottom")
		(5 "F.SilkS" user "Ref Des/Silkscreen Top")
		(7 "B.SilkS" user "Ref Des/Silkscreen Bottom")
		(1 "F.Mask" user "Board Geometry/Soldermask Top")
		(3 "B.Mask" user "Board Geometry/Soldermask Bottom")
		(17 "Dwgs.User" user "User.Drawings")
		(19 "Cmts.User" user "User.Comments")
		(21 "Eco1.User" user "User.Eco1")
		(23 "Eco2.User" user "User.Eco2")
		(25 "Edge.Cuts" user "Board Geometry/Outline")
		(27 "Margin" user)
		(31 "F.CrtYd" user "Package Geometry/Place Bound Top")
		(29 "B.CrtYd" user "Package Geometry/Place Bound Bottom")
		(35 "F.Fab" user "Ref Des/Assembly Top")
		(33 "B.Fab" user "Ref Des/Assembly Bottom")
	)
	(footprint ""
		(layer "F.Cu")
		(at 375.80697 -408.517344 -90)
		(property "Reference" "C872"
			(at 0 0 270)
			(layer "F.SilkS")
			(hide yes)
			(effects
				(font
					(size 1.27 1.27)
				)
			)
		)
		(property "Value" ""
			(at 0 0 270)
			(layer "F.Fab")
			(effects
				(font
					(size 1.27 1.27)
				)
			)
		)
		(duplicate_pad_numbers_are_jumpers no)
		(fp_line
			(start -0.299974 0.150114)
			(end -0.299974 -0.150114)
			(stroke
				(width 0.1)
				(type default)
			)
			(layer "F.Fab")
		)
		(fp_line
			(start 0.299974 0.150114)
			(end -0.299974 0.150114)
			(stroke
				(width 0.1)
				(type default)
			)
			(layer "F.Fab")
		)
		(fp_line
			(start -0.299974 -0.150114)
			(end 0.299974 -0.150114)
			(stroke
				(width 0.1)
				(type default)
			)
			(layer "F.Fab")
		)
		(fp_line
			(start 0.299974 -0.150114)
			(end 0.299974 0.150114)
			(stroke
				(width 0.1)
				(type default)
			)
			(layer "F.Fab")
		)
		(pad "1" smd rect
			(at -0.2667 0 270)
			(size 0.3048 0.381)
			(layers "F.Cu" "F.Mask" "F.Paste")
			(net "P5E_CPU0_PE3_TX_C_DN<14>")
		)
		(pad "2" smd rect
			(at 0.2667 0 270)
			(size 0.3048 0.381)
			(layers "F.Cu" "F.Mask" "F.Paste")
			(net "P5E_CPU0_PE3_TX_DN<14>")
		)
	)
	(footprint ""
		(layer "F.Cu")
		(at 134.225538 -345.393264 90)
		(property "Reference" "PC479"
			(at 0 0 90)
			(layer "F.SilkS")
			(hide yes)
			(effects
				(font
					(size 1.27 1.27)
				)
			)
		)
		(property "Value" ""
			(at 0 0 90)
			(layer "F.Fab")
			(effects
				(font
					(size 1.27 1.27)
				)
			)
		)
		(duplicate_pad_numbers_are_jumpers no)
		(fp_line
			(start 0.7874 -0.4064)
			(end 0.7874 0.4064)
			(stroke
				(width 0.1524)
				(type default)
			)
			(layer "F.SilkS")
		)
		(fp_line
			(start -0.7874 -0.4064)
			(end 0.7874 -0.4064)
			(stroke
				(width 0.1524)
				(type default)
			)
			(layer "F.SilkS")
		)
		(fp_line
			(start 0.7874 0.4064)
			(end -0.7874 0.4064)
			(stroke
				(width 0.1524)
				(type default)
			)
			(layer "F.SilkS")
		)
		(fp_line
			(start -0.7874 0.4064)
			(end -0.7874 -0.4064)
			(stroke
				(width 0.1524)
				(type default)
			)
			(layer "F.SilkS")
		)
		(fp_line
			(start -0.12065 -0.305054)
			(end -0.12065 -0.2794)
			(stroke
				(width 0.1)
				(type default)
			)
			(layer "F.Fab")
		)
		(fp_line
			(start -0.67945 -0.305054)
			(end -0.12065 -0.305054)
			(stroke
				(width 0.1)
				(type default)
			)
			(layer "F.Fab")
		)
		(fp_line
			(start 0.67945 -0.3048)
			(end 0.67945 0.3048)
			(stroke
				(width 0.1)
				(type default)
			)
			(layer "F.Fab")
		)
		(fp_line
			(start 0.12065 -0.3048)
			(end 0.67945 -0.3048)
			(stroke
				(width 0.1)
				(type default)
			)
			(layer "F.Fab")
		)
		(fp_line
			(start 0.12065 -0.2794)
			(end 0.12065 -0.3048)
			(stroke
				(width 0.1)
				(type default)
			)
			(layer "F.Fab")
		)
		(fp_line
			(start -0.12065 -0.2794)
			(end 0.12065 -0.2794)
			(stroke
				(width 0.1)
				(type default)
			)
			(layer "F.Fab")
		)
		(fp_line
			(start 0.120396 0.2794)
			(end -0.12065 0.2794)
			(stroke
				(width 0.1)
				(type default)
			)
			(layer "F.Fab")
		)
		(fp_line
			(start -0.12065 0.2794)
			(end -0.12065 0.3048)
			(stroke
				(width 0.1)
				(type default)
			)
			(layer "F.Fab")
		)
		(fp_line
			(start 0.67945 0.3048)
			(end 0.120396 0.3048)
			(stroke
				(width 0.1)
				(type default)
			)
			(layer "F.Fab")
		)
		(fp_line
			(start 0.120396 0.3048)
			(end 0.120396 0.2794)
			(stroke
				(width 0.1)
				(type default)
			)
			(layer "F.Fab")
		)
		(fp_line
			(start -0.12065 0.3048)
			(end -0.67945 0.3048)
			(stroke
				(width 0.1)
				(type default)
			)
			(layer "F.Fab")
		)
		(fp_line
			(start -0.67945 0.3048)
			(end -0.67945 -0.305054)
			(stroke
				(width 0.1)
				(type default)
			)
			(layer "F.Fab")
		)
		(pad "1" smd circle
			(at -0.40005 0 90)
			(size 0 0)
			(layers "F.Cu" "F.Mask" "F.Paste")
			(net "PVCCIN_CPU1_VDD8")
		)
		(pad "2" smd circle
			(at 0.40005 0 90)
			(size 0 0)
			(layers "F.Cu" "F.Mask" "F.Paste")
			(net "GND")
		)
	)
	(footprint ""
		(layer "F.Cu")
		(at 416.169348 -353.312984 -90)
		(property "Reference" "PL33"
			(at -2.921254 7.125208 0)
			(unlocked yes)
			(layer "F.SilkS")
			(effects
				(font
					(size 0.7874 0.5842)
					(thickness 0.1524)
				)
				(justify left)
			)
		)
		(property "Value" ""
			(at 0 0 270)
			(layer "F.Fab")
			(effects
				(font
					(size 1.27 1.27)
				)
			)
		)
		(duplicate_pad_numbers_are_jumpers no)
		(fp_line
			(start -4.99999 3.750056)
			(end -4.99999 2.2479)
			(stroke
				(width 0.1524)
				(type default)
			)
			(layer "F.SilkS")
		)
		(fp_line
			(start 0 3.750056)
			(end -4.99999 3.750056)
			(stroke
				(width 0.1524)
				(type default)
			)
			(layer "F.SilkS")
		)
		(fp_line
			(start 4.99999 3.750056)
			(end 0 3.750056)
			(stroke
				(width 0.1524)
				(type default)
			)
			(layer "F.SilkS")
		)
		(fp_line
			(start 4.99999 2.2352)
			(end 4.99999 3.750056)
			(stroke
				(width 0.1524)
				(type default)
			)
			(layer "F.SilkS")
		)
		(fp_line
			(start -4.99999 -2.2479)
			(end -4.99999 -3.750056)
			(stroke
				(width 0.1524)
				(type default)
			)
			(layer "F.SilkS")
		)
		(fp_line
			(start -4.99999 -3.750056)
			(end 4.99999 -3.750056)
			(stroke
				(width 0.1524)
				(type default)
			)
			(layer "F.SilkS")
		)
		(fp_line
			(start 4.99999 -3.750056)
			(end 4.99999 -2.2479)
			(stroke
				(width 0.1524)
				(type default)
			)
			(layer "F.SilkS")
		)
		(fp_line
			(start -4.99999 3.750056)
			(end -4.99999 -3.750056)
			(stroke
				(width 0.1)
				(type default)
			)
			(layer "F.Fab")
		)
		(fp_line
			(start 0 3.750056)
			(end -4.99999 3.750056)
			(stroke
				(width 0.1)
				(type default)
			)
			(layer "F.Fab")
		)
		(fp_line
			(start 4.99999 3.750056)
			(end 0 3.750056)
			(stroke
				(width 0.1)
				(type default)
			)
			(layer "F.Fab")
		)
		(fp_line
			(start -4.99999 -3.750056)
			(end 4.99999 -3.750056)
			(stroke
				(width 0.1)
				(type default)
			)
			(layer "F.Fab")
		)
		(fp_line
			(start 4.99999 -3.750056)
			(end 4.99999 3.750056)
			(stroke
				(width 0.1)
				(type default)
			)
			(layer "F.Fab")
		)
		(pad "1" smd rect
			(at -3.299968 0 270)
			(size 3.302 4.2164)
			(layers "F.Cu" "F.Mask" "F.Paste")
			(net "SW_PVCCFA_EHV_FIVRA_CPU0_SW1")
		)
		(pad "2" smd rect
			(at 3.299968 0 270)
			(size 3.302 4.2164)
			(layers "F.Cu" "F.Mask" "F.Paste")
			(net "PVCCFA_EHV_FIVRA_CPU0")
		)
	)
	(footprint ""
		(layer "F.Cu")
		(at 109.599476 -79.078836)
		(property "Reference" "D91"
			(at -54.33441 38.649402 90)
			(unlocked yes)
			(layer "F.SilkS")
			(effects
				(font
					(size 0.635 0.4064)
					(thickness 0.1524)
				)
				(justify left)
			)
		)
		(property "Value" ""
			(at 0 0 0)
			(layer "F.Fab")
			(effects
				(font
					(size 1.27 1.27)
				)
			)
		)
		(duplicate_pad_numbers_are_jumpers no)
		(fp_line
			(start -0.90678 0.4826)
			(end -0.90678 -0.4699)
			(stroke
				(width 0.1524)
				(type default)
			)
			(layer "F.SilkS")
		)
		(fp_line
			(start -0.89408 -0.4826)
			(end 0.90678 -0.4826)
			(stroke
				(width 0.1524)
				(type default)
			)
			(layer "F.SilkS")
		)
		(fp_line
			(start -0.79248 -0.4826)
			(end 1.03378 -0.4826)
			(stroke
				(width 0.1524)
				(type default)
			)
			(layer "F.SilkS")
		)
		(fp_line
			(start -0.64008 -0.4826)
			(end 1.16078 -0.4826)
			(stroke
				(width 0.1524)
				(type default)
			)
			(layer "F.SilkS")
		)
		(fp_line
			(start 0.90678 -0.4826)
			(end 0.90678 0.4826)
			(stroke
				(width 0.1524)
				(type default)
			)
			(layer "F.SilkS")
		)
		(fp_line
			(start 0.90678 0.4826)
			(end -0.90678 0.4826)
			(stroke
				(width 0.1524)
				(type default)
			)
			(layer "F.SilkS")
		)
		(fp_line
			(start 1.03378 -0.4826)
			(end 1.03378 0.4826)
			(stroke
				(width 0.1524)
				(type default)
			)
			(layer "F.SilkS")
		)
		(fp_line
			(start 1.03378 0.4826)
			(end -0.79248 0.4826)
			(stroke
				(width 0.1524)
				(type default)
			)
			(layer "F.SilkS")
		)
		(fp_line
			(start 1.16078 -0.4826)
			(end 1.16078 0.4826)
			(stroke
				(width 0.1524)
				(type default)
			)
			(layer "F.SilkS")
		)
		(fp_line
			(start 1.16078 0.4826)
			(end -0.64008 0.4826)
			(stroke
				(width 0.1524)
				(type default)
			)
			(layer "F.SilkS")
		)
		(fp_line
			(start -0.499872 -0.249936)
			(end 0.499872 -0.249936)
			(stroke
				(width 0.1)
				(type default)
			)
			(layer "F.Fab")
		)
		(fp_line
			(start -0.499872 0.249936)
			(end -0.499872 -0.249936)
			(stroke
				(width 0.1)
				(type default)
			)
			(layer "F.Fab")
		)
		(fp_line
			(start 0.499872 -0.249936)
			(end 0.499872 0.249936)
			(stroke
				(width 0.1)
				(type default)
			)
			(layer "F.Fab")
		)
		(fp_line
			(start 0.499872 0.249936)
			(end -0.499872 0.249936)
			(stroke
				(width 0.1)
				(type default)
			)
			(layer "F.Fab")
		)
		(pad "A" smd rect
			(at -0.47498 0)
			(size 0.6096 0.7112)
			(layers "F.Cu" "F.Mask" "F.Paste")
			(net "LED_PWRGD_P1V8_PCH_AUX")
		)
		(pad "C" smd rect
			(at 0.47498 0)
			(size 0.6096 0.7112)
			(layers "F.Cu" "F.Mask" "F.Paste")
			(net "LED_PWRGD_P1V8_PCH_AUX_D")
		)
	)
	(footprint ""
		(layer "F.Cu")
		(at 108.05668 -60.086748)
		(property "Reference" "C1288"
			(at 0 0 0)
			(layer "F.SilkS")
			(hide yes)
			(effects
				(font
					(size 1.27 1.27)
				)
			)
		)
		(property "Value" ""
			(at 0 0 0)
			(layer "F.Fab")
			(effects
				(font
					(size 1.27 1.27)
				)
			)
		)
		(duplicate_pad_numbers_are_jumpers no)
		(fp_line
			(start -0.7874 -0.4064)
			(end 0.7874 -0.4064)
			(stroke
				(width 0.1524)
				(type default)
			)
			(layer "F.SilkS")
		)
		(fp_line
			(start -0.7874 0.4064)
			(end -0.7874 -0.4064)
			(stroke
				(width 0.1524)
				(type default)
			)
			(layer "F.SilkS")
		)
		(fp_line
			(start 0.7874 -0.4064)
			(end 0.7874 0.4064)
			(stroke
				(width 0.1524)
				(type default)
			)
			(layer "F.SilkS")
		)
		(fp_line
			(start 0.7874 0.4064)
			(end -0.7874 0.4064)
			(stroke
				(width 0.1524)
				(type default)
			)
			(layer "F.SilkS")
		)
		(fp_line
			(start -0.67945 -0.305054)
			(end -0.12065 -0.305054)
			(stroke
				(width 0.1)
				(type default)
			)
			(layer "F.Fab")
		)
		(fp_line
			(start -0.67945 0.3048)
			(end -0.67945 -0.305054)
			(stroke
				(width 0.1)
				(type default)
			)
			(layer "F.Fab")
		)
		(fp_line
			(start -0.12065 -0.305054)
			(end -0.12065 -0.2794)
			(stroke
				(width 0.1)
				(type default)
			)
			(layer "F.Fab")
		)
		(fp_line
			(start -0.12065 -0.2794)
			(end 0.12065 -0.2794)
			(stroke
				(width 0.1)
				(type default)
			)
			(layer "F.Fab")
		)
		(fp_line
			(start -0.12065 0.2794)
			(end -0.12065 0.3048)
			(stroke
				(width 0.1)
				(type default)
			)
			(layer "F.Fab")
		)
		(fp_line
			(start -0.12065 0.3048)
			(end -0.67945 0.3048)
			(stroke
				(width 0.1)
				(type default)
			)
			(layer "F.Fab")
		)
		(fp_line
			(start 0.120396 0.2794)
			(end -0.12065 0.2794)
			(stroke
				(width 0.1)
				(type default)
			)
			(layer "F.Fab")
		)
		(fp_line
			(start 0.120396 0.3048)
			(end 0.120396 0.2794)
			(stroke
				(width 0.1)
				(type default)
			)
			(layer "F.Fab")
		)
		(fp_line
			(start 0.12065 -0.3048)
			(end 0.67945 -0.3048)
			(stroke
				(width 0.1)
				(type default)
			)
			(layer "F.Fab")
		)
		(fp_line
			(start 0.12065 -0.2794)
			(end 0.12065 -0.3048)
			(stroke
				(width 0.1)
				(type default)
			)
			(layer "F.Fab")
		)
		(fp_line
			(start 0.67945 -0.3048)
			(end 0.67945 0.3048)
			(stroke
				(width 0.1)
				(type default)
			)
			(layer "F.Fab")
		)
		(fp_line
			(start 0.67945 0.3048)
			(end 0.120396 0.3048)
			(stroke
				(width 0.1)
				(type default)
			)
			(layer "F.Fab")
		)
		(pad "1" smd circle
			(at -0.40005 0)
			(size 0 0)
			(layers "F.Cu" "F.Mask" "F.Paste")
			(net "P3V3_AUX")
		)
		(pad "2" smd circle
			(at 0.40005 0)
			(size 0 0)
			(layers "F.Cu" "F.Mask" "F.Paste")
			(net "GND")
		)
	)
	(footprint ""
		(layer "F.Cu")
		(at 160.83788 -105.755948 180)
		(property "Reference" "R2845"
			(at 0 0 180)
			(layer "F.SilkS")
			(hide yes)
			(effects
				(font
					(size 1.27 1.27)
				)
			)
		)
		(property "Value" ""
			(at 0 0 180)
			(layer "F.Fab")
			(effects
				(font
					(size 1.27 1.27)
				)
			)
		)
		(duplicate_pad_numbers_are_jumpers no)
		(fp_line
			(start 0.7874 0.4064)
			(end -0.7874 0.4064)
			(stroke
				(width 0.1524)
				(type default)
			)
			(layer "F.SilkS")
		)
		(fp_line
			(start 0.7874 -0.4064)
			(end 0.7874 0.4064)
			(stroke
				(width 0.1524)
				(type default)
			)
			(layer "F.SilkS")
		)
		(fp_line
			(start -0.7874 0.4064)
			(end -0.7874 -0.4064)
			(stroke
				(width 0.1524)
				(type default)
			)
			(layer "F.SilkS")
		)
		(fp_line
			(start -0.7874 -0.4064)
			(end 0.7874 -0.4064)
			(stroke
				(width 0.1524)
				(type default)
			)
			(layer "F.SilkS")
		)
		(fp_line
			(start 0.67945 0.3048)
			(end 0.120396 0.3048)
			(stroke
				(width 0.1)
				(type default)
			)
			(layer "F.Fab")
		)
		(fp_line
			(start 0.67945 -0.3048)
			(end 0.67945 0.3048)
			(stroke
				(width 0.1)
				(type default)
			)
			(layer "F.Fab")
		)
		(fp_line
			(start 0.12065 -0.2794)
			(end 0.12065 -0.3048)
			(stroke
				(width 0.1)
				(type default)
			)
			(layer "F.Fab")
		)
		(fp_line
			(start 0.12065 -0.3048)
			(end 0.67945 -0.3048)
			(stroke
				(width 0.1)
				(type default)
			)
			(layer "F.Fab")
		)
		(fp_line
			(start 0.120396 0.3048)
			(end 0.120396 0.2794)
			(stroke
				(width 0.1)
				(type default)
			)
			(layer "F.Fab")
		)
		(fp_line
			(start 0.120396 0.2794)
			(end -0.12065 0.2794)
			(stroke
				(width 0.1)
				(type default)
			)
			(layer "F.Fab")
		)
		(fp_line
			(start -0.12065 0.3048)
			(end -0.67945 0.3048)
			(stroke
				(width 0.1)
				(type default)
			)
			(layer "F.Fab")
		)
		(fp_line
			(start -0.12065 0.2794)
			(end -0.12065 0.3048)
			(stroke
				(width 0.1)
				(type default)
			)
			(layer "F.Fab")
		)
		(fp_line
			(start -0.12065 -0.2794)
			(end 0.12065 -0.2794)
			(stroke
				(width 0.1)
				(type default)
			)
			(layer "F.Fab")
		)
		(fp_line
			(start -0.12065 -0.305054)
			(end -0.12065 -0.2794)
			(stroke
				(width 0.1)
				(type default)
			)
			(layer "F.Fab")
		)
		(fp_line
			(start -0.67945 0.3048)
			(end -0.67945 -0.305054)
			(stroke
				(width 0.1)
				(type default)
			)
			(layer "F.Fab")
		)
		(fp_line
			(start -0.67945 -0.305054)
			(end -0.12065 -0.305054)
			(stroke
				(width 0.1)
				(type default)
			)
			(layer "F.Fab")
		)
		(pad "1" smd circle
			(at -0.40005 0 180)
			(size 0 0)
			(layers "F.Cu" "F.Mask" "F.Paste")
			(net "BMC_MONITER")
		)
		(pad "2" smd circle
			(at 0.40005 0 180)
			(size 0 0)
			(layers "F.Cu" "F.Mask" "F.Paste")
			(net "BMC_MONITER_R")
		)
	)
	(footprint ""
		(layer "F.Cu")
		(at 406.124664 -358.436926 180)
		(property "Reference" "R1238"
			(at 0 0 180)
			(layer "F.SilkS")
			(hide yes)
			(effects
				(font
					(size 1.27 1.27)
				)
			)
		)
		(property "Value" ""
			(at 0 0 180)
			(layer "F.Fab")
			(effects
				(font
					(size 1.27 1.27)
				)
			)
		)
		(duplicate_pad_numbers_are_jumpers no)
		(fp_line
			(start 0.7874 0.4064)
			(end -0.7874 0.4064)
			(stroke
				(width 0.1524)
				(type default)
			)
			(layer "F.SilkS")
		)
		(fp_line
			(start 0.7874 -0.4064)
			(end 0.7874 0.4064)
			(stroke
				(width 0.1524)
				(type default)
			)
			(layer "F.SilkS")
		)
		(fp_line
			(start -0.7874 0.4064)
			(end -0.7874 -0.4064)
			(stroke
				(width 0.1524)
				(type default)
			)
			(layer "F.SilkS")
		)
		(fp_line
			(start -0.7874 -0.4064)
			(end 0.7874 -0.4064)
			(stroke
				(width 0.1524)
				(type default)
			)
			(layer "F.SilkS")
		)
		(fp_line
			(start 0.67945 0.3048)
			(end 0.120396 0.3048)
			(stroke
				(width 0.1)
				(type default)
			)
			(layer "F.Fab")
		)
		(fp_line
			(start 0.67945 -0.3048)
			(end 0.67945 0.3048)
			(stroke
				(width 0.1)
				(type default)
			)
			(layer "F.Fab")
		)
		(fp_line
			(start 0.12065 -0.2794)
			(end 0.12065 -0.3048)
			(stroke
				(width 0.1)
				(type default)
			)
			(layer "F.Fab")
		)
		(fp_line
			(start 0.12065 -0.3048)
			(end 0.67945 -0.3048)
			(stroke
				(width 0.1)
				(type default)
			)
			(layer "F.Fab")
		)
		(fp_line
			(start 0.120396 0.3048)
			(end 0.120396 0.2794)
			(stroke
				(width 0.1)
				(type default)
			)
			(layer "F.Fab")
		)
		(fp_line
			(start 0.120396 0.2794)
			(end -0.12065 0.2794)
			(stroke
				(width 0.1)
				(type default)
			)
			(layer "F.Fab")
		)
		(fp_line
			(start -0.12065 0.3048)
			(end -0.67945 0.3048)
			(stroke
				(width 0.1)
				(type default)
			)
			(layer "F.Fab")
		)
		(fp_line
			(start -0.12065 0.2794)
			(end -0.12065 0.3048)
			(stroke
				(width 0.1)
				(type default)
			)
			(layer "F.Fab")
		)
		(fp_line
			(start -0.12065 -0.2794)
			(end 0.12065 -0.2794)
			(stroke
				(width 0.1)
				(type default)
			)
			(layer "F.Fab")
		)
		(fp_line
			(start -0.12065 -0.305054)
			(end -0.12065 -0.2794)
			(stroke
				(width 0.1)
				(type default)
			)
			(layer "F.Fab")
		)
		(fp_line
			(start -0.67945 0.3048)
			(end -0.67945 -0.305054)
			(stroke
				(width 0.1)
				(type default)
			)
			(layer "F.Fab")
		)
		(fp_line
			(start -0.67945 -0.305054)
			(end -0.12065 -0.305054)
			(stroke
				(width 0.1)
				(type default)
			)
			(layer "F.Fab")
		)
		(pad "1" smd circle
			(at -0.40005 0 180)
			(size 0 0)
			(layers "F.Cu" "F.Mask" "F.Paste")
			(net "GND")
		)
		(pad "2" smd circle
			(at 0.40005 0 180)
			(size 0 0)
			(layers "F.Cu" "F.Mask" "F.Paste")
			(net "PUD_XTAL_CPU0_MODE0")
		)
	)
)
